FILE_TYPE=LIBRARY_PARTS;
primitive 'CONN6_HBC1031L200D8H';
  pin
    '1':
      PIN_NUMBER='(1)';
      BIDIRECTIONAL='TRUE';
      INPUT_LOAD='(-0.01,0.01)';
      OUTPUT_LOAD='(1.0,-1.0)';
    '2':
      PIN_NUMBER='(2)';
      BIDIRECTIONAL='TRUE';
      INPUT_LOAD='(-0.01,0.01)';
      OUTPUT_LOAD='(1.0,-1.0)';
    '3':
      PIN_NUMBER='(3)';
      BIDIRECTIONAL='TRUE';
      INPUT_LOAD='(-0.01,0.01)';
      OUTPUT_LOAD='(1.0,-1.0)';
    '4':
      PIN_NUMBER='(4)';
      BIDIRECTIONAL='TRUE';
      INPUT_LOAD='(-0.01,0.01)';
      OUTPUT_LOAD='(1.0,-1.0)';
    '5':
      PIN_NUMBER='(5)';
      BIDIRECTIONAL='TRUE';
      INPUT_LOAD='(-0.01,0.01)';
      OUTPUT_LOAD='(1.0,-1.0)';
    '6':
      PIN_NUMBER='(6)';
      BIDIRECTIONAL='TRUE';
      INPUT_LOAD='(-0.01,0.01)';
      OUTPUT_LOAD='(1.0,-1.0)';
  end_pin;
  body
    PART_NAME='CONN6_HBC1031L200D8H';
    BODY_NAME='CONN6_HBC1031L200D8H';
    PHYS_DES_PREFIX='J';
    CLASS='IO';
  end_body;
end_primitive;

END.
